(kicad_pcb
	(version 20221018)
	(generator pcbnew)
	(general
    (thickness 1.6)
  )
	(paper "A4")
	(title_block
    (title "NUC Computer Cluster Power Breakout HW")
    (date "2023-10-18")
    (rev "1.4.3")
    (company "Antmicro Ltd.")
		(comment 9 "footprints 214-214 of 234")
	)
	(layers
    (0 "F.Cu" mixed)
    (1 "In1.Cu" power)
    (2 "In2.Cu" mixed)
    (31 "B.Cu" power)
    (32 "B.Adhes" user "B.Adhesive")
    (33 "F.Adhes" user "F.Adhesive")
    (34 "B.Paste" user)
    (35 "F.Paste" user)
    (36 "B.SilkS" user "B.Silkscreen")
    (37 "F.SilkS" user "F.Silkscreen")
    (38 "B.Mask" user)
    (39 "F.Mask" user)
    (40 "Dwgs.User" user "User.Drawings")
    (41 "Cmts.User" user "User.Comments")
    (42 "Eco1.User" user "User.Eco1")
    (43 "Eco2.User" user "User.Eco2")
    (44 "Edge.Cuts" user)
    (45 "Margin" user)
    (46 "B.CrtYd" user "B.Courtyard")
    (47 "F.CrtYd" user "F.Courtyard")
    (48 "B.Fab" user)
    (49 "F.Fab" user)
  )
	(footprint "antmicro-footprints:QFN-56-1EP_8x8mm_P0.5mm" (layer "F.Cu")
    (at 160 119.2 180)
    (descr "QFN 56 Pin")
    (tags "QFN")
    (property "Author" "Antmicro")
    (property "License" "Apache-2.0")
    (property "MPN" "FT4232H-56Q-REEL")
    (property "Manufacturer" "FTDI Chip")
    (property "Sheetfile" "ftdi-module.kicad_sch")
    (property "Sheetname" "FTDI")
    (property "ki_description" "Interface Bridges, USB to UART, MPSSE, 1.62 V, 1.98 V, VQFN, 56 Pins, -40 °C")
    (property "ki_keywords" "SMT, INTERFACE, IC, CONTROLLER, USB, UART, I2C, SPI, JTAG")
    (attr smd)
    (fp_text reference "U5" (at 4.55 4.45 180) (layer "F.SilkS")
        (effects (font (size 0.7 0.7) (thickness 0.15)) (justify left bottom))
    )
    (fp_text value "FT4232H_VQFN" (at 0 5.32 180) (layer "F.Fab")
        (effects (font (size 0.7 0.7) (thickness 0.15)) (justify left bottom))
    )
    (fp_text user "Author: Antmicro" (at -4.4 8.519 180) (layer "F.Fab") hide
        (effects (font (size 0.7 0.7) (thickness 0.15)) (justify left bottom))
    )
    (fp_text user "${REFERENCE}" (at -4.4 7.32 180) (layer "F.Fab") hide
        (effects (font (size 0.7 0.7) (thickness 0.15)) (justify left bottom))
    )
    (fp_text user "License: Apache-2.0" (at -4.4 9.719 180) (layer "F.Fab") hide
        (effects (font (size 0.7 0.7) (thickness 0.15)) (justify left bottom))
    )
    (fp_line (start -4.111 -3.635) (end -4.111 -4.111)
      (stroke (width 0.15) (type solid)) (layer "F.SilkS"))
    (fp_line (start -4.111 4.11) (end -4.111 3.634)
      (stroke (width 0.15) (type solid)) (layer "F.SilkS"))
    (fp_line (start -3.635 -4.111) (end -4.111 -4.111)
      (stroke (width 0.15) (type solid)) (layer "F.SilkS"))
    (fp_line (start -3.635 4.11) (end -4.111 4.11)
      (stroke (width 0.15) (type solid)) (layer "F.SilkS"))
    (fp_line (start 3.634 -4.111) (end 4.11 -4.111)
      (stroke (width 0.15) (type solid)) (layer "F.SilkS"))
    (fp_line (start 3.634 4.11) (end 4.11 4.11)
      (stroke (width 0.15) (type solid)) (layer "F.SilkS"))
    (fp_line (start 4.11 -4.111) (end 4.11 -3.635)
      (stroke (width 0.15) (type solid)) (layer "F.SilkS"))
    (fp_line (start 4.11 4.11) (end 4.11 3.634)
      (stroke (width 0.15) (type solid)) (layer "F.SilkS"))
    (fp_circle (center -4.35 -3.6) (end -4.3 -3.6)
      (stroke (width 0.15) (type solid)) (fill solid) (layer "F.SilkS"))
    (fp_rect (start 4.4 4.4) (end -4.4 -4.4)
      (stroke (width 0.05) (type solid)) (fill none) (layer "F.CrtYd"))
    (fp_line (start -4 -3) (end -3 -4)
      (stroke (width 0.15) (type solid)) (layer "F.Fab"))
    (fp_rect (start 4 4) (end -4 -4)
      (stroke (width 0.15) (type solid)) (fill none) (layer "F.Fab"))
    (pad "" smd roundrect (at -2.101 -2.101 180) (size 1.13 1.13) (layers "F.Paste") (roundrect_rratio 0.221239))
    (pad "" smd roundrect (at -2.101 -0.7 180) (size 1.13 1.13) (layers "F.Paste") (roundrect_rratio 0.221239))
    (pad "" smd roundrect (at -2.101 0.699 180) (size 1.13 1.13) (layers "F.Paste") (roundrect_rratio 0.221239))
    (pad "" smd roundrect (at -2.101 2.1 180) (size 1.13 1.13) (layers "F.Paste") (roundrect_rratio 0.221239))
    (pad "" smd roundrect (at -0.7 -2.101 180) (size 1.13 1.13) (layers "F.Paste") (roundrect_rratio 0.221239))
    (pad "" smd roundrect (at -0.7 -0.7 180) (size 1.13 1.13) (layers "F.Paste") (roundrect_rratio 0.221239))
    (pad "" smd roundrect (at -0.7 0.699 180) (size 1.13 1.13) (layers "F.Paste") (roundrect_rratio 0.221239))
    (pad "" smd roundrect (at -0.7 2.1 180) (size 1.13 1.13) (layers "F.Paste") (roundrect_rratio 0.221239))
    (pad "" smd roundrect (at 0.699 -2.101 180) (size 1.13 1.13) (layers "F.Paste") (roundrect_rratio 0.221239))
    (pad "" smd roundrect (at 0.699 -0.7 180) (size 1.13 1.13) (layers "F.Paste") (roundrect_rratio 0.221239))
    (pad "" smd roundrect (at 0.699 0.699 180) (size 1.13 1.13) (layers "F.Paste") (roundrect_rratio 0.221239))
    (pad "" smd roundrect (at 0.699 2.1 180) (size 1.13 1.13) (layers "F.Paste") (roundrect_rratio 0.221239))
    (pad "" smd roundrect (at 2.1 -2.101 180) (size 1.13 1.13) (layers "F.Paste") (roundrect_rratio 0.221239))
    (pad "" smd roundrect (at 2.1 -0.7 180) (size 1.13 1.13) (layers "F.Paste") (roundrect_rratio 0.221239))
    (pad "" smd roundrect (at 2.1 0.699 180) (size 1.13 1.13) (layers "F.Paste") (roundrect_rratio 0.221239))
    (pad "" smd roundrect (at 2.1 2.1 180) (size 1.13 1.13) (layers "F.Paste") (roundrect_rratio 0.221239))
    (pad "1" smd roundrect (at -3.938 -3.25 180) (size 0.875 0.3) (layers "F.Cu" "F.Paste" "F.Mask") (roundrect_rratio 0.25)
      (net 121 "unconnected-(U5-EECS-Pad1)") (pinfunction "EECS") (pintype "bidirectional+no_connect"))
    (pad "2" smd roundrect (at -3.938 -2.75 180) (size 0.875 0.3) (layers "F.Cu" "F.Paste" "F.Mask") (roundrect_rratio 0.25)
      (net 7 "1V8_FT") (pinfunction "V_{CORE}") (pintype "power_in"))
    (pad "3" smd roundrect (at -3.938 -2.25 180) (size 0.875 0.3) (layers "F.Cu" "F.Paste" "F.Mask") (roundrect_rratio 0.25)
      (net 5 "/FTDI/OSCI") (pinfunction "OSCI") (pintype "input"))
    (pad "4" smd roundrect (at -3.938 -1.75 180) (size 0.875 0.3) (layers "F.Cu" "F.Paste" "F.Mask") (roundrect_rratio 0.25)
      (net 125 "/FTDI/OSCO") (pinfunction "OSCO") (pintype "output"))
    (pad "5" smd roundrect (at -3.938 -1.25 180) (size 0.875 0.3) (layers "F.Cu" "F.Paste" "F.Mask") (roundrect_rratio 0.25)
      (net 8 "/FTDI/FTDI_VPHY") (pinfunction "V_{PHY}") (pintype "power_in"))
    (pad "6" smd roundrect (at -3.938 -0.75 180) (size 0.875 0.3) (layers "F.Cu" "F.Paste" "F.Mask") (roundrect_rratio 0.25)
      (net 104 "Net-(U5-REF)") (pinfunction "REF") (pintype "input"))
    (pad "7" smd roundrect (at -3.938 -0.25 180) (size 0.875 0.3) (layers "F.Cu" "F.Paste" "F.Mask") (roundrect_rratio 0.25)
      (net 15 "/FTDI/USB_D-") (pinfunction "D-") (pintype "bidirectional"))
    (pad "8" smd roundrect (at -3.938 0.249 180) (size 0.875 0.3) (layers "F.Cu" "F.Paste" "F.Mask") (roundrect_rratio 0.25)
      (net 14 "/FTDI/USB_D+") (pinfunction "D+") (pintype "bidirectional"))
    (pad "9" smd roundrect (at -3.938 0.749 180) (size 0.875 0.3) (layers "F.Cu" "F.Paste" "F.Mask") (roundrect_rratio 0.25)
      (net 6 "/FTDI/FTDI_VPLL") (pinfunction "V_{PLL}") (pintype "power_in"))
    (pad "10" smd roundrect (at -3.938 1.249 180) (size 0.875 0.3) (layers "F.Cu" "F.Paste" "F.Mask") (roundrect_rratio 0.25)
      (net 77 "GNDD") (pinfunction "TEST") (pintype "input"))
    (pad "11" smd roundrect (at -3.938 1.749 180) (size 0.875 0.3) (layers "F.Cu" "F.Paste" "F.Mask") (roundrect_rratio 0.25)
      (net 31 "/FTDI/FTDI_RST") (pinfunction "~{RESET}") (pintype "input"))
    (pad "12" smd roundrect (at -3.938 2.249 180) (size 0.875 0.3) (layers "F.Cu" "F.Paste" "F.Mask") (roundrect_rratio 0.25)
      (net 81 "SCL_FTDI") (pinfunction "ADBUS0") (pintype "bidirectional"))
    (pad "13" smd roundrect (at -3.938 2.749 180) (size 0.875 0.3) (layers "F.Cu" "F.Paste" "F.Mask") (roundrect_rratio 0.25)
      (net 9 "/FTDI/SDA_FTDI_2") (pinfunction "ADBUS1") (pintype "bidirectional"))
    (pad "14" smd roundrect (at -3.938 3.249 180) (size 0.875 0.3) (layers "F.Cu" "F.Paste" "F.Mask") (roundrect_rratio 0.25)
      (net 80 "SDA_FTDI") (pinfunction "ADBUS2") (pintype "bidirectional"))
    (pad "15" smd roundrect (at -3.25 3.937 270) (size 0.875 0.3) (layers "F.Cu" "F.Paste" "F.Mask") (roundrect_rratio 0.25)
      (net 33 "/FTDI/WP") (pinfunction "ADBUS3") (pintype "bidirectional"))
    (pad "16" smd roundrect (at -2.75 3.937 270) (size 0.875 0.3) (layers "F.Cu" "F.Paste" "F.Mask") (roundrect_rratio 0.25)
      (net 76 "VCC3V3_USB") (pinfunction "V_{CCIO}") (pintype "power_in"))
    (pad "17" smd roundrect (at -2.25 3.937 270) (size 0.875 0.3) (layers "F.Cu" "F.Paste" "F.Mask") (roundrect_rratio 0.25)
      (net 122 "unconnected-(U5-ADBUS4-Pad17)") (pinfunction "ADBUS4") (pintype "bidirectional+no_connect"))
    (pad "18" smd roundrect (at -1.75 3.937 270) (size 0.875 0.3) (layers "F.Cu" "F.Paste" "F.Mask") (roundrect_rratio 0.25)
      (net 123 "unconnected-(U5-ADBUS5-Pad18)") (pinfunction "ADBUS5") (pintype "bidirectional+no_connect"))
    (pad "19" smd roundrect (at -1.25 3.937 270) (size 0.875 0.3) (layers "F.Cu" "F.Paste" "F.Mask") (roundrect_rratio 0.25)
      (net 124 "unconnected-(U5-ADBUS6-Pad19)") (pinfunction "ADBUS6") (pintype "bidirectional+no_connect"))
    (pad "20" smd roundrect (at -0.75 3.937 270) (size 0.875 0.3) (layers "F.Cu" "F.Paste" "F.Mask") (roundrect_rratio 0.25)
      (net 126 "unconnected-(U5-ADBUS7-Pad20)") (pinfunction "ADBUS7") (pintype "bidirectional+no_connect"))
    (pad "21" smd roundrect (at -0.25 3.937 270) (size 0.875 0.3) (layers "F.Cu" "F.Paste" "F.Mask") (roundrect_rratio 0.25)
      (net 77 "GNDD") (pinfunction "GND") (pintype "power_in"))
    (pad "22" smd roundrect (at 0.249 3.937 270) (size 0.875 0.3) (layers "F.Cu" "F.Paste" "F.Mask") (roundrect_rratio 0.25)
      (net 127 "unconnected-(U5-BDBUS0-Pad22)") (pinfunction "BDBUS0") (pintype "bidirectional+no_connect"))
    (pad "23" smd roundrect (at 0.749 3.937 270) (size 0.875 0.3) (layers "F.Cu" "F.Paste" "F.Mask") (roundrect_rratio 0.25)
      (net 116 "Net-(U5-BDBUS1)") (pinfunction "BDBUS1") (pintype "bidirectional"))
    (pad "24" smd roundrect (at 1.249 3.937 270) (size 0.875 0.3) (layers "F.Cu" "F.Paste" "F.Mask") (roundrect_rratio 0.25)
      (net 128 "unconnected-(U5-BDBUS2-Pad24)") (pinfunction "BDBUS2") (pintype "bidirectional+no_connect"))
    (pad "25" smd roundrect (at 1.749 3.937 270) (size 0.875 0.3) (layers "F.Cu" "F.Paste" "F.Mask") (roundrect_rratio 0.25)
      (net 129 "unconnected-(U5-BDBUS3-Pad25)") (pinfunction "BDBUS3") (pintype "bidirectional+no_connect"))
    (pad "26" smd roundrect (at 2.249 3.937 270) (size 0.875 0.3) (layers "F.Cu" "F.Paste" "F.Mask") (roundrect_rratio 0.25)
      (net 130 "unconnected-(U5-BDBUS4-Pad26)") (pinfunction "BDBUS4") (pintype "bidirectional+no_connect"))
    (pad "27" smd roundrect (at 2.749 3.937 270) (size 0.875 0.3) (layers "F.Cu" "F.Paste" "F.Mask") (roundrect_rratio 0.25)
      (net 131 "unconnected-(U5-BDBUS5-Pad27)") (pinfunction "BDBUS5") (pintype "bidirectional+no_connect"))
    (pad "28" smd roundrect (at 3.249 3.937 270) (size 0.875 0.3) (layers "F.Cu" "F.Paste" "F.Mask") (roundrect_rratio 0.25)
      (net 132 "unconnected-(U5-BDBUS6-Pad28)") (pinfunction "BDBUS6") (pintype "bidirectional+no_connect"))
    (pad "29" smd roundrect (at 3.937 3.249 180) (size 0.875 0.3) (layers "F.Cu" "F.Paste" "F.Mask") (roundrect_rratio 0.25)
      (net 133 "unconnected-(U5-BDBUS7-Pad29)") (pinfunction "BDBUS7") (pintype "bidirectional+no_connect"))
    (pad "30" smd roundrect (at 3.937 2.749 180) (size 0.875 0.3) (layers "F.Cu" "F.Paste" "F.Mask") (roundrect_rratio 0.25)
      (net 134 "unconnected-(U5-~{SUSPEND}-Pad30)") (pinfunction "~{SUSPEND}") (pintype "output+no_connect"))
    (pad "31" smd roundrect (at 3.937 2.249 180) (size 0.875 0.3) (layers "F.Cu" "F.Paste" "F.Mask") (roundrect_rratio 0.25)
      (net 7 "1V8_FT") (pinfunction "V_{CORE}") (pintype "passive"))
    (pad "32" smd roundrect (at 3.937 1.749 180) (size 0.875 0.3) (layers "F.Cu" "F.Paste" "F.Mask") (roundrect_rratio 0.25)
      (net 135 "unconnected-(U5-CDBUS0-Pad32)") (pinfunction "CDBUS0") (pintype "bidirectional+no_connect"))
    (pad "33" smd roundrect (at 3.937 1.249 180) (size 0.875 0.3) (layers "F.Cu" "F.Paste" "F.Mask") (roundrect_rratio 0.25)
      (net 138 "unconnected-(U5-CDBUS1-Pad33)") (pinfunction "CDBUS1") (pintype "bidirectional+no_connect"))
    (pad "34" smd roundrect (at 3.937 0.749 180) (size 0.875 0.3) (layers "F.Cu" "F.Paste" "F.Mask") (roundrect_rratio 0.25)
      (net 139 "unconnected-(U5-CDBUS2-Pad34)") (pinfunction "CDBUS2") (pintype "bidirectional+no_connect"))
    (pad "35" smd roundrect (at 3.937 0.249 180) (size 0.875 0.3) (layers "F.Cu" "F.Paste" "F.Mask") (roundrect_rratio 0.25)
      (net 140 "unconnected-(U5-CDBUS3-Pad35)") (pinfunction "CDBUS3") (pintype "bidirectional+no_connect"))
    (pad "36" smd roundrect (at 3.937 -0.25 180) (size 0.875 0.3) (layers "F.Cu" "F.Paste" "F.Mask") (roundrect_rratio 0.25)
      (net 76 "VCC3V3_USB") (pinfunction "V_{CCIO}") (pintype "passive"))
    (pad "37" smd roundrect (at 3.937 -0.75 180) (size 0.875 0.3) (layers "F.Cu" "F.Paste" "F.Mask") (roundrect_rratio 0.25)
      (net 141 "unconnected-(U5-CDBUS4-Pad37)") (pinfunction "CDBUS4") (pintype "bidirectional+no_connect"))
    (pad "38" smd roundrect (at 3.937 -1.25 180) (size 0.875 0.3) (layers "F.Cu" "F.Paste" "F.Mask") (roundrect_rratio 0.25)
      (net 142 "unconnected-(U5-CDBUS5-Pad38)") (pinfunction "CDBUS5") (pintype "bidirectional+no_connect"))
    (pad "39" smd roundrect (at 3.937 -1.75 180) (size 0.875 0.3) (layers "F.Cu" "F.Paste" "F.Mask") (roundrect_rratio 0.25)
      (net 143 "unconnected-(U5-CDBUS6-Pad39)") (pinfunction "CDBUS6") (pintype "bidirectional+no_connect"))
    (pad "40" smd roundrect (at 3.937 -2.25 180) (size 0.875 0.3) (layers "F.Cu" "F.Paste" "F.Mask") (roundrect_rratio 0.25)
      (net 146 "unconnected-(U5-CDBUS7-Pad40)") (pinfunction "CDBUS7") (pintype "bidirectional+no_connect"))
    (pad "41" smd roundrect (at 3.937 -2.75 180) (size 0.875 0.3) (layers "F.Cu" "F.Paste" "F.Mask") (roundrect_rratio 0.25)
      (net 77 "GNDD") (pinfunction "GND") (pintype "passive"))
    (pad "42" smd roundrect (at 3.937 -3.25 180) (size 0.875 0.3) (layers "F.Cu" "F.Paste" "F.Mask") (roundrect_rratio 0.25)
      (net 148 "unconnected-(U5-DDBUS0-Pad42)") (pinfunction "DDBUS0") (pintype "bidirectional+no_connect"))
    (pad "43" smd roundrect (at 3.249 -3.938 270) (size 0.875 0.3) (layers "F.Cu" "F.Paste" "F.Mask") (roundrect_rratio 0.25)
      (net 7 "1V8_FT") (pinfunction "V_{REGOUT}") (pintype "power_out"))
    (pad "44" smd roundrect (at 2.749 -3.938 270) (size 0.875 0.3) (layers "F.Cu" "F.Paste" "F.Mask") (roundrect_rratio 0.25)
      (net 76 "VCC3V3_USB") (pinfunction "V_{REGIN}") (pintype "power_in"))
    (pad "45" smd roundrect (at 2.249 -3.938 270) (size 0.875 0.3) (layers "F.Cu" "F.Paste" "F.Mask") (roundrect_rratio 0.25)
      (net 77 "GNDD") (pinfunction "GND") (pintype "passive"))
    (pad "46" smd roundrect (at 1.749 -3.938 270) (size 0.875 0.3) (layers "F.Cu" "F.Paste" "F.Mask") (roundrect_rratio 0.25)
      (net 149 "unconnected-(U5-DDBUS1-Pad46)") (pinfunction "DDBUS1") (pintype "bidirectional+no_connect"))
    (pad "47" smd roundrect (at 1.249 -3.938 270) (size 0.875 0.3) (layers "F.Cu" "F.Paste" "F.Mask") (roundrect_rratio 0.25)
      (net 150 "unconnected-(U5-DDBUS2-Pad47)") (pinfunction "DDBUS2") (pintype "bidirectional+no_connect"))
    (pad "48" smd roundrect (at 0.749 -3.938 270) (size 0.875 0.3) (layers "F.Cu" "F.Paste" "F.Mask") (roundrect_rratio 0.25)
      (net 151 "unconnected-(U5-DDBUS3-Pad48)") (pinfunction "DDBUS3") (pintype "bidirectional+no_connect"))
    (pad "49" smd roundrect (at 0.249 -3.938 270) (size 0.875 0.3) (layers "F.Cu" "F.Paste" "F.Mask") (roundrect_rratio 0.25)
      (net 152 "unconnected-(U5-DDBUS4-Pad49)") (pinfunction "DDBUS4") (pintype "bidirectional+no_connect"))
    (pad "50" smd roundrect (at -0.25 -3.938 270) (size 0.875 0.3) (layers "F.Cu" "F.Paste" "F.Mask") (roundrect_rratio 0.25)
      (net 76 "VCC3V3_USB") (pinfunction "V_{CCIO}") (pintype "passive"))
    (pad "51" smd roundrect (at -0.75 -3.938 270) (size 0.875 0.3) (layers "F.Cu" "F.Paste" "F.Mask") (roundrect_rratio 0.25)
      (net 153 "unconnected-(U5-DDBUS5-Pad51)") (pinfunction "DDBUS5") (pintype "bidirectional+no_connect"))
    (pad "52" smd roundrect (at -1.25 -3.938 270) (size 0.875 0.3) (layers "F.Cu" "F.Paste" "F.Mask") (roundrect_rratio 0.25)
      (net 154 "unconnected-(U5-DDBUS6-Pad52)") (pinfunction "DDBUS6") (pintype "bidirectional+no_connect"))
    (pad "53" smd roundrect (at -1.75 -3.938 270) (size 0.875 0.3) (layers "F.Cu" "F.Paste" "F.Mask") (roundrect_rratio 0.25)
      (net 155 "unconnected-(U5-DDBUS7-Pad53)") (pinfunction "DDBUS7") (pintype "bidirectional+no_connect"))
    (pad "54" smd roundrect (at -2.25 -3.938 270) (size 0.875 0.3) (layers "F.Cu" "F.Paste" "F.Mask") (roundrect_rratio 0.25)
      (net 156 "unconnected-(U5-~{PWR_{EN}}-Pad54)") (pinfunction "~{PWR_{EN}}") (pintype "output+no_connect"))
    (pad "55" smd roundrect (at -2.75 -3.938 270) (size 0.875 0.3) (layers "F.Cu" "F.Paste" "F.Mask") (roundrect_rratio 0.25)
      (net 157 "unconnected-(U5-EEDATA-Pad55)") (pinfunction "EEDATA") (pintype "bidirectional+no_connect"))
    (pad "56" smd roundrect (at -3.25 -3.938 270) (size 0.875 0.3) (layers "F.Cu" "F.Paste" "F.Mask") (roundrect_rratio 0.25)
      (net 158 "unconnected-(U5-EECLK-Pad56)") (pinfunction "EECLK") (pintype "output+no_connect"))
    (pad "57" smd rect (at 0 0 180) (size 5.9 5.9) (layers "F.Cu" "F.Mask")
      (net 77 "GNDD") (pinfunction "GND") (pintype "passive"))
  )
)
